# T6G (Grand Teton) — schematic parts with pin connectivity, parts 8081–8081 of 8303; source: Cadence DE-HDL packaged netlist (pstxprt.dat, pstxnet.dat, pstchip.dat)

U25  GENOA_SP5  SOCKET6096_13568-001 IO  pkg SOCKET6096_93-4X120-45XA  page 10  (pins 673-1008 of 6096)
  AJ44  G1_TXN5  OUT  = GMI_CPU0_G1_CPU1_G3_TX_DN<5>
  AJ45  VSS_AJ45  POWER  = GND
  AJ46  G1_TXP8  OUT  = GMI_CPU0_G1_CPU1_G3_TX_DP<8>
  AJ47  G1_TXN8  OUT  = GMI_CPU0_G1_CPU1_G3_TX_DN<8>
  AJ48  VSS_AJ48  POWER  = GND
  AJ49  G1_TXP11  OUT  = GMI_CPU0_G1_CPU1_G3_TX_DP<11>
  AJ50  G1_TXN11  OUT  = GMI_CPU0_G1_CPU1_G3_TX_DN<11>
  AJ51  VSS_AJ51  POWER  = GND
  AJ52  G1_TXP14  OUT  = GMI_CPU0_G1_CPU1_G3_TX_DP<14>
  AJ53  G1_TXN14  OUT  = GMI_CPU0_G1_CPU1_G3_TX_DN<14>
  AJ54  VSS_AJ54  POWER  = GND
  AJ55  MCA_DATA31  BI  = M_C_CPU0_SA_DQ<31>
  AJ56  VSS_AJ56  POWER  = GND
  AJ57  MCA_CHECK0  BI  = M_C_CPU0_SA_CB<0>
  AJ58  VDDIO_AJ58  POWER  = PVDDIO_P0
  AJ59  MDA_DATA31  BI  = M_D_CPU0_SA_DQ<31>
  AJ60  MDA_CHECK0  BI  = M_D_CPU0_SA_CB<0>
  AJ61  VSS_AJ61  POWER  = GND
  AJ62  MBA_DATA31  BI  = M_B_CPU0_SA_DQ<31>
  AJ63  VSS_AJ63  POWER  = GND
  AJ64  MBA_CHECK0  BI  = M_B_CPU0_SA_CB<0>
  AJ65  VDDIO_AJ65  POWER  = PVDDIO_P0
  AJ66  MFA_DATA31  BI  = M_F_CPU0_SA_DQ<31>
  AJ67  MFA_CHECK0  BI  = M_F_CPU0_SA_CB<0>
  AJ68  VSS_AJ68  POWER  = GND
  AJ69  MEA_DATA31  BI  = M_E_CPU0_SA_DQ<31>
  AJ70  VSS_AJ70  POWER  = GND
  AJ71  MEA_CHECK0  BI  = M_E_CPU0_SA_CB<0>
  AJ72  VDDIO_AJ72  POWER  = PVDDIO_P0
  AJ73  MAA_DATA31  BI  = M_A_CPU0_SA_DQ<31>
  AJ74  MAA_CHECK0  BI  = M_A_CPU0_SA_CB<0>
  AJ75  VSS_AJ75  POWER  = GND
  AK2  MGA_CHECK2  BI  = M_G_CPU0_SA_CB<2>
  AK3  VSS_AK3  POWER  = GND
  AK4  MGA_CHECK1  BI  = M_G_CPU0_SA_CB<1>
  AK5  VSS_AK5  POWER  = GND
  AK6  MKA_CHECK2  BI  = M_K_CPU0_SA_CB<2>
  AK7  MKA_CHECK1  BI  = M_K_CPU0_SA_CB<1>
  AK8  VSS_AK8  POWER  = GND
  AK9  MLA_CHECK2  BI  = M_L_CPU0_SA_CB<2>
  AK10  VSS_AK10  POWER  = GND
  AK11  MLA_CHECK1  BI  = M_L_CPU0_SA_CB<1>
  AK12  VSS_AK12  POWER  = GND
  AK13  MHA_CHECK2  BI  = M_H_CPU0_SA_CB<2>
  AK14  MHA_CHECK1  BI  = M_H_CPU0_SA_CB<1>
  AK15  VSS_AK15  POWER  = GND
  AK16  MJA_CHECK2  BI  = M_J_CPU0_SA_CB<2>
  AK17  VSS_AK17  POWER  = GND
  AK18  MJA_CHECK1  BI  = M_J_CPU0_SA_CB<1>
  AK19  VSS_AK19  POWER  = GND
  AK20  MIA_CHECK2  BI  = M_I_CPU0_SA_CB<2>
  AK21  MIA_CHECK1  BI  = M_I_CPU0_SA_CB<1>
  AK22  VSS_AK22  POWER  = GND
  AK23  VDDCR_CPU0_AK23  POWER  = PVDDCR_CPU0_P0
  AK24  VDDCR_CPU0_AK24  POWER  = PVDDCR_CPU0_P0
  AK25  VSS_AK25  POWER  = GND
  AK26  VDDCR_CPU0_AK26  POWER  = PVDDCR_CPU0_P0
  AK27  VDDCR_CPU0_AK27  POWER  = PVDDCR_CPU0_P0
  AK28  VSS_AK28  POWER  = GND
  AK29  VDDCR_CPU0_AK29  POWER  = PVDDCR_CPU0_P0
  AK30  VDDCR_CPU0_AK30  POWER  = PVDDCR_CPU0_P0
  AK31  VSS_AK31  POWER  = GND
  AK32  VDDCR_CPU0_AK32  POWER  = PVDDCR_CPU0_P0
  AK33  VDDCR_CPU0_AK33  POWER  = PVDDCR_CPU0_P0
  AK34  VSS_AK34  POWER  = GND
  AK35  \g3_rxn12||sata34_rxn\  IN  = P5E_CPU0_G3_RX_DN<12>
  AK36  \g3_rxp12||sata34_rxp\  IN  = P5E_CPU0_G3_RX_DP<12>
  AK37  VSS_AK37  POWER  = GND
  AK39  VSS_AK39  POWER  = GND
  AK40  G1_TXP3  OUT  = GMI_CPU0_G1_CPU1_G3_TX_DP<3>
  AK41  G1_TXN3  OUT  = GMI_CPU0_G1_CPU1_G3_TX_DN<3>
  AK42  VSS_AK42  POWER  = GND
  AK43  VDDCR_CPU0_AK43  POWER  = PVDDCR_CPU0_P0
  AK44  VDDCR_CPU0_AK44  POWER  = PVDDCR_CPU0_P0
  AK45  VSS_AK45  POWER  = GND
  AK46  VDDCR_CPU0_AK46  POWER  = PVDDCR_CPU0_P0
  AK47  VDDCR_CPU0_AK47  POWER  = PVDDCR_CPU0_P0
  AK48  VSS_AK48  POWER  = GND
  AK49  VDDCR_CPU0_AK49  POWER  = PVDDCR_CPU0_P0
  AK50  VDDCR_CPU0_AK50  POWER  = PVDDCR_CPU0_P0
  AK51  VSS_AK51  POWER  = GND
  AK52  VDDCR_CPU0_AK52  POWER  = PVDDCR_CPU0_P0
  AK53  VDDCR_CPU0_AK53  POWER  = PVDDCR_CPU0_P0
  AK54  VSS_AK54  POWER  = GND
  AK55  MCA_CHECK1  BI  = M_C_CPU0_SA_CB<1>
  AK56  MCA_CHECK2  BI  = M_C_CPU0_SA_CB<2>
  AK57  VSS_AK57  POWER  = GND
  AK58  MDA_CHECK1  BI  = M_D_CPU0_SA_CB<1>
  AK59  VSS_AK59  POWER  = GND
  AK60  MDA_CHECK2  BI  = M_D_CPU0_SA_CB<2>
  AK61  VSS_AK61  POWER  = GND
  AK62  MBA_CHECK1  BI  = M_B_CPU0_SA_CB<1>
  AK63  MBA_CHECK2  BI  = M_B_CPU0_SA_CB<2>
  AK64  VSS_AK64  POWER  = GND
  AK65  MFA_CHECK1  BI  = M_F_CPU0_SA_CB<1>
  AK66  VSS_AK66  POWER  = GND
  AK67  MFA_CHECK2  BI  = M_F_CPU0_SA_CB<2>
  AK68  VSS_AK68  POWER  = GND
  AK69  MEA_CHECK1  BI  = M_E_CPU0_SA_CB<1>
  AK70  MEA_CHECK2  BI  = M_E_CPU0_SA_CB<2>
  AK71  VSS_AK71  POWER  = GND
  AK72  MAA_CHECK1  BI  = M_A_CPU0_SA_CB<1>
  AK73  VSS_AK73  POWER  = GND
  AK74  MAA_CHECK2  BI  = M_A_CPU0_SA_CB<2>
  AL1  VSS_AL1  POWER  = GND
  AL2  MGA_DQS_H4  BI  = M_G_CPU0_SA_DQS_DP<4>
  AL3  MGA_CHECK3  BI  = M_G_CPU0_SA_CB<3>
  AL4  VSS_AL4  POWER  = GND
  AL5  MKA_DQS_H4  BI  = M_K_CPU0_SA_DQS_DP<4>
  AL6  VSS_AL6  POWER  = GND
  AL7  MKA_CHECK3  BI  = M_K_CPU0_SA_CB<3>
  AL8  VSS_AL8  POWER  = GND
  AL9  MLA_DQS_H4  BI  = M_L_CPU0_SA_DQS_DP<4>
  AL10  MLA_CHECK3  BI  = M_L_CPU0_SA_CB<3>
  AL11  VSS_AL11  POWER  = GND
  AL12  MHA_DQS_H4  BI  = M_H_CPU0_SA_DQS_DP<4>
  AL13  VSS_AL13  POWER  = GND
  AL14  MHA_CHECK3  BI  = M_H_CPU0_SA_CB<3>
  AL15  VSS_AL15  POWER  = GND
  AL16  MJA_DQS_H4  BI  = M_J_CPU0_SA_DQS_DP<4>
  AL17  MJA_CHECK3  BI  = M_J_CPU0_SA_CB<3>
  AL18  VSS_AL18  POWER  = GND
  AL19  MIA_DQS_H4  BI  = M_I_CPU0_SA_DQS_DP<4>
  AL20  VSS_AL20  POWER  = GND
  AL21  MIA_CHECK3  BI  = M_I_CPU0_SA_CB<3>
  AL22  VSS_AL22  POWER  = GND
  AL23  \g3_rxn0||sata20_rxn\  IN  = P5E_CPU0_G3_RX_DN<0>
  AL24  \g3_rxp0||sata20_rxp\  IN  = P5E_CPU0_G3_RX_DP<0>
  AL25  VSS_AL25  POWER  = GND
  AL26  \g3_rxn3||sata23_rxn\  IN  = P5E_CPU0_G3_RX_DN<3>
  AL27  \g3_rxp3||sata23_rxp\  IN  = P5E_CPU0_G3_RX_DP<3>
  AL28  VSS_AL28  POWER  = GND
  AL29  \g3_rxn6||sata26_rxn\  IN  = P5E_CPU0_G3_RX_DN<6>
  AL30  \g3_rxp6||sata26_rxp\  IN  = P5E_CPU0_G3_RX_DP<6>
  AL31  VSS_AL31  POWER  = GND
  AL32  \g3_rxn9||sata31_rxn\  IN  = P5E_CPU0_G3_RX_DN<9>
  AL33  \g3_rxp9||sata31_rxp\  IN  = P5E_CPU0_G3_RX_DP<9>
  AL34  VSS_AL34  POWER  = GND
  AL35  VDDCR_CPU0_AL35  POWER  = PVDDCR_CPU0_P0
  AL36  VDDCR_CPU0_AL36  POWER  = PVDDCR_CPU0_P0
  AL40  VDDCR_CPU0_AL40  POWER  = PVDDCR_CPU0_P0
  AL41  VDDCR_CPU0_AL41  POWER  = PVDDCR_CPU0_P0
  AL42  VSS_AL42  POWER  = GND
  AL43  G1_TXP6  OUT  = GMI_CPU0_G1_CPU1_G3_TX_DP<6>
  AL44  G1_TXN6  OUT  = GMI_CPU0_G1_CPU1_G3_TX_DN<6>
  AL45  VSS_AL45  POWER  = GND
  AL46  G1_TXP9  OUT  = GMI_CPU0_G1_CPU1_G3_TX_DP<9>
  AL47  G1_TXN9  OUT  = GMI_CPU0_G1_CPU1_G3_TX_DN<9>
  AL48  VSS_AL48  POWER  = GND
  AL49  G1_TXP12  OUT  = GMI_CPU0_G1_CPU1_G3_TX_DP<12>
  AL50  G1_TXN12  OUT  = GMI_CPU0_G1_CPU1_G3_TX_DN<12>
  AL51  VSS_AL51  POWER  = GND
  AL52  G1_TXP15  OUT  = GMI_CPU0_G1_CPU1_G3_TX_DP<15>
  AL53  G1_TXN15  OUT  = GMI_CPU0_G1_CPU1_G3_TX_DN<15>
  AL54  VSS_AL54  POWER  = GND
  AL55  MCA_CHECK3  BI  = M_C_CPU0_SA_CB<3>
  AL56  VSS_AL56  POWER  = GND
  AL57  MCA_DQS_H4  BI  = M_C_CPU0_SA_DQS_DP<4>
  AL58  VSS_AL58  POWER  = GND
  AL59  MDA_CHECK3  BI  = M_D_CPU0_SA_CB<3>
  AL60  MDA_DQS_H4  BI  = M_D_CPU0_SA_DQS_DP<4>
  AL61  VSS_AL61  POWER  = GND
  AL62  MBA_CHECK3  BI  = M_B_CPU0_SA_CB<3>
  AL63  VSS_AL63  POWER  = GND
  AL64  MBA_DQS_H4  BI  = M_B_CPU0_SA_DQS_DP<4>
  AL65  VSS_AL65  POWER  = GND
  AL66  MFA_CHECK3  BI  = M_F_CPU0_SA_CB<3>
  AL67  MFA_DQS_H4  BI  = M_F_CPU0_SA_DQS_DP<4>
  AL68  VSS_AL68  POWER  = GND
  AL69  MEA_CHECK3  BI  = M_E_CPU0_SA_CB<3>
  AL70  VSS_AL70  POWER  = GND
  AL71  MEA_DQS_H4  BI  = M_E_CPU0_SA_DQS_DP<4>
  AL72  VSS_AL72  POWER  = GND
  AL73  MAA_CHECK3  BI  = M_A_CPU0_SA_CB<3>
  AL74  MAA_DQS_H4  BI  = M_A_CPU0_SA_DQS_DP<4>
  AL75  VSS_AL75  POWER  = GND
  AM2  MGA_DQS_L4  BI  = M_G_CPU0_SA_DQS_DN<4>
  AM3  VSS_AM3  POWER  = GND
  AM4  MGA_DQS_L9  BI  = M_G_CPU0_SA_DQS_DN<9>
  AM5  VDDCR_SOC_AM5  POWER  = PVDDCR_SOC_P0
  AM6  MKA_DQS_L4  BI  = M_K_CPU0_SA_DQS_DN<4>
  AM7  MKA_DQS_L9  BI  = M_K_CPU0_SA_DQS_DN<9>
  AM8  VSS_AM8  POWER  = GND
  AM9  MLA_DQS_L4  BI  = M_L_CPU0_SA_DQS_DN<4>
  AM10  VSS_AM10  POWER  = GND
  AM11  MLA_DQS_L9  BI  = M_L_CPU0_SA_DQS_DN<9>
  AM12  VDDCR_SOC_AM12  POWER  = PVDDCR_SOC_P0
  AM13  MHA_DQS_L4  BI  = M_H_CPU0_SA_DQS_DN<4>
  AM14  MHA_DQS_L9  BI  = M_H_CPU0_SA_DQS_DN<9>
  AM15  VSS_AM15  POWER  = GND
  AM16  MJA_DQS_L4  BI  = M_J_CPU0_SA_DQS_DN<4>
  AM17  VSS_AM17  POWER  = GND
  AM18  MJA_DQS_L9  BI  = M_J_CPU0_SA_DQS_DN<9>
  AM19  VDDCR_SOC_AM19  POWER  = PVDDCR_SOC_P0
  AM20  MIA_DQS_L4  BI  = M_I_CPU0_SA_DQS_DN<4>
  AM21  MIA_DQS_L9  BI  = M_I_CPU0_SA_DQS_DN<9>
  AM22  VDDCR_SOC_AM22  POWER  = PVDDCR_SOC_P0
  AM23  VSS_AM23  POWER  = GND
  AM24  VSS_AM24  POWER  = GND
  AM25  VSS_AM25  POWER  = GND
  AM26  VSS_AM26  POWER  = GND
  AM27  VSS_AM27  POWER  = GND
  AM28  VSS_AM28  POWER  = GND
  AM29  VSS_AM29  POWER  = GND
  AM30  VSS_AM30  POWER  = GND
  AM31  VSS_AM31  POWER  = GND
  AM32  VSS_AM32  POWER  = GND
  AM33  VSS_AM33  POWER  = GND
  AM34  VSS_AM34  POWER  = GND
  AM35  \g3_rxn14||sata36_rxn\  IN  = P5E_CPU0_G3_RX_DN<14>
  AM36  \g3_rxp14||sata36_rxp\  IN  = P5E_CPU0_G3_RX_DP<14>
  AM37  VSS_AM37  POWER  = GND
  AM39  VSS_AM39  POWER  = GND
  AM40  G1_TXP1  OUT  = GMI_CPU0_G1_CPU1_G3_TX_DP<1>
  AM41  G1_TXN1  OUT  = GMI_CPU0_G1_CPU1_G3_TX_DN<1>
  AM42  VSS_AM42  POWER  = GND
  AM43  VSS_AM43  POWER  = GND
  AM44  VSS_AM44  POWER  = GND
  AM45  VSS_AM45  POWER  = GND
  AM46  VSS_AM46  POWER  = GND
  AM47  VSS_AM47  POWER  = GND
  AM48  VSS_AM48  POWER  = GND
  AM49  VSS_AM49  POWER  = GND
  AM50  VSS_AM50  POWER  = GND
  AM51  VSS_AM51  POWER  = GND
  AM52  VSS_AM52  POWER  = GND
  AM53  VSS_AM53  POWER  = GND
  AM54  VDDIO_AM54  POWER  = PVDDIO_P0
  AM55  MCA_DQS_L9  BI  = M_C_CPU0_SA_DQS_DN<9>
  AM56  MCA_DQS_L4  BI  = M_C_CPU0_SA_DQS_DN<4>
  AM57  VDDIO_AM57  POWER  = PVDDIO_P0
  AM58  MDA_DQS_L9  BI  = M_D_CPU0_SA_DQS_DN<9>
  AM59  VSS_AM59  POWER  = GND
  AM60  MDA_DQS_L4  BI  = M_D_CPU0_SA_DQS_DN<4>
  AM61  VSS_AM61  POWER  = GND
  AM62  MBA_DQS_L9  BI  = M_B_CPU0_SA_DQS_DN<9>
  AM63  MBA_DQS_L4  BI  = M_B_CPU0_SA_DQS_DN<4>
  AM64  VDDIO_AM64  POWER  = PVDDIO_P0
  AM65  MFA_DQS_L9  BI  = M_F_CPU0_SA_DQS_DN<9>
  AM66  VSS_AM66  POWER  = GND
  AM67  MFA_DQS_L4  BI  = M_F_CPU0_SA_DQS_DN<4>
  AM68  VSS_AM68  POWER  = GND
  AM69  MEA_DQS_L9  BI  = M_E_CPU0_SA_DQS_DN<9>
  AM70  MEA_DQS_L4  BI  = M_E_CPU0_SA_DQS_DN<4>
  AM71  VDDIO_AM71  POWER  = PVDDIO_P0
  AM72  MAA_DQS_L9  BI  = M_A_CPU0_SA_DQS_DN<9>
  AM73  VSS_AM73  POWER  = GND
  AM74  MAA_DQS_L4  BI  = M_A_CPU0_SA_DQS_DN<4>
  AN1  VSS_AN1  POWER  = GND
  AN2  MGA_CHECK4  BI  = M_G_CPU0_SA_CB<4>
  AN3  MGA_DQS_H9  BI  = M_G_CPU0_SA_DQS_DP<9>
  AN4  VSS_AN4  POWER  = GND
  AN5  MKA_CHECK4  BI  = M_K_CPU0_SA_CB<4>
  AN6  VSS_AN6  POWER  = GND
  AN7  MKA_DQS_H9  BI  = M_K_CPU0_SA_DQS_DP<9>
  AN8  VSS_AN8  POWER  = GND
  AN9  MLA_CHECK4  BI  = M_L_CPU0_SA_CB<4>
  AN10  MLA_DQS_H9  BI  = M_L_CPU0_SA_DQS_DP<9>
  AN11  VSS_AN11  POWER  = GND
  AN12  MHA_CHECK4  BI  = M_H_CPU0_SA_CB<4>
  AN13  VSS_AN13  POWER  = GND
  AN14  MHA_DQS_H9  BI  = M_H_CPU0_SA_DQS_DP<9>
  AN15  VSS_AN15  POWER  = GND
  AN16  MJA_CHECK4  BI  = M_J_CPU0_SA_CB<4>
  AN17  MJA_DQS_H9  BI  = M_J_CPU0_SA_DQS_DP<9>
  AN18  VSS_AN18  POWER  = GND
  AN19  MIA_CHECK4  BI  = M_I_CPU0_SA_CB<4>
  AN20  VSS_AN20  POWER  = GND
  AN21  MIA_DQS_H9  BI  = M_I_CPU0_SA_DQS_DP<9>
  AN22  VSS_AN22  POWER  = GND
  AN23  \g3_rxn2||sata22_rxn\  IN  = P5E_CPU0_G3_RX_DN<2>
  AN24  \g3_rxp2||sata22_rxp\  IN  = P5E_CPU0_G3_RX_DP<2>
  AN25  VSS_AN25  POWER  = GND
  AN26  \g3_rxn5||sata25_rxn\  IN  = P5E_CPU0_G3_RX_DN<5>
  AN27  \g3_rxp5||sata25_rxp\  IN  = P5E_CPU0_G3_RX_DP<5>
  AN28  VSS_AN28  POWER  = GND
  AN29  \g3_rxn8||sata30_rxn\  IN  = P5E_CPU0_G3_RX_DN<8>
  AN30  \g3_rxp8||sata30_rxp\  IN  = P5E_CPU0_G3_RX_DP<8>
  AN31  VSS_AN31  POWER  = GND
  AN32  \g3_rxn11||sata33_rxn\  IN  = P5E_CPU0_G3_RX_DN<11>
  AN33  \g3_rxp11||sata33_rxp\  IN  = P5E_CPU0_G3_RX_DP<11>
  AN34  VSS_AN34  POWER  = GND
  AN35  VSS_AN35  POWER  = GND
  AN36  VSS_AN36  POWER  = GND
  AN40  VSS_AN40  POWER  = GND
  AN41  VSS_AN41  POWER  = GND
  AN42  VSS_AN42  POWER  = GND
  AN43  G1_TXP4  OUT  = GMI_CPU0_G1_CPU1_G3_TX_DP<4>
  AN44  G1_TXN4  OUT  = GMI_CPU0_G1_CPU1_G3_TX_DN<4>
  AN45  VSS_AN45  POWER  = GND
  AN46  G1_TXP7  OUT  = GMI_CPU0_G1_CPU1_G3_TX_DP<7>
  AN47  G1_TXN7  OUT  = GMI_CPU0_G1_CPU1_G3_TX_DN<7>
  AN48  VSS_AN48  POWER  = GND
  AN49  G1_TXP10  OUT  = GMI_CPU0_G1_CPU1_G3_TX_DP<10>
  AN50  G1_TXN10  OUT  = GMI_CPU0_G1_CPU1_G3_TX_DN<10>
  AN51  VSS_AN51  POWER  = GND
  AN52  G1_TXP13  OUT  = GMI_CPU0_G1_CPU1_G3_TX_DP<13>
  AN53  G1_TXN13  OUT  = GMI_CPU0_G1_CPU1_G3_TX_DN<13>
  AN54  VSS_AN54  POWER  = GND
  AN55  MCA_DQS_H9  BI  = M_C_CPU0_SA_DQS_DP<9>
  AN56  VSS_AN56  POWER  = GND
  AN57  MCA_CHECK4  BI  = M_C_CPU0_SA_CB<4>
  AN58  VSS_AN58  POWER  = GND
  AN59  MDA_DQS_H9  BI  = M_D_CPU0_SA_DQS_DP<9>
  AN60  MDA_CHECK4  BI  = M_D_CPU0_SA_CB<4>
  AN61  VSS_AN61  POWER  = GND
  AN62  MBA_DQS_H9  BI  = M_B_CPU0_SA_DQS_DP<9>
  AN63  VSS_AN63  POWER  = GND
  AN64  MBA_CHECK4  BI  = M_B_CPU0_SA_CB<4>
  AN65  VSS_AN65  POWER  = GND
  AN66  MFA_DQS_H9  BI  = M_F_CPU0_SA_DQS_DP<9>
  AN67  MFA_CHECK4  BI  = M_F_CPU0_SA_CB<4>
  AN68  VSS_AN68  POWER  = GND
  AN69  MEA_DQS_H9  BI  = M_E_CPU0_SA_DQS_DP<9>
  AN70  VSS_AN70  POWER  = GND
  AN71  MEA_CHECK4  BI  = M_E_CPU0_SA_CB<4>
  AN72  VSS_AN72  POWER  = GND
  AN73  MAA_DQS_H9  BI  = M_A_CPU0_SA_DQS_DP<9>
  AN74  MAA_CHECK4  BI  = M_A_CPU0_SA_CB<4>
  AN75  VSS_AN75  POWER  = GND
  AP2  MGA_CHECK6  BI  = M_G_CPU0_SA_CB<6>
  AP3  VSS_AP3  POWER  = GND
  AP4  MGA_CHECK5  BI  = M_G_CPU0_SA_CB<5>
  AP5  VSS_AP5  POWER  = GND
  AP6  MKA_CHECK6  BI  = M_K_CPU0_SA_CB<6>
  AP7  MKA_CHECK5  BI  = M_K_CPU0_SA_CB<5>
  AP8  VSS_AP8  POWER  = GND
  AP9  MLA_CHECK6  BI  = M_L_CPU0_SA_CB<6>
  AP10  VSS_AP10  POWER  = GND
  AP11  MLA_CHECK5  BI  = M_L_CPU0_SA_CB<5>
  AP12  VSS_AP12  POWER  = GND
  AP13  MHA_CHECK6  BI  = M_H_CPU0_SA_CB<6>
  AP14  MHA_CHECK5  BI  = M_H_CPU0_SA_CB<5>
  AP15  VSS_AP15  POWER  = GND
  AP16  MJA_CHECK6  BI  = M_J_CPU0_SA_CB<6>
  AP17  VSS_AP17  POWER  = GND
